# TIMECARD (Time Appliance Project (Time Card)) — schematic netlist excerpt (pin names and nets, part order shuffled) for the footprints in the layout excerpt that follows; sources: Cadence DE-HDL packaged netlist, KiCad conversion of R4006-B0001-02_R01.brd

R272  RESISTOR  100OHM 1%  pkg SMC_0402R_H016  page 26 : \1\ = FPGA_OUT_SMA1_LED_RED_N ; \2\ = UNNAMED_14_LED4PV14_I265_3
TP186  TP_PIONT  pkg TP010CT020B030_PTH  page 25 : \1\ = IO_L23N_16

(kicad_pcb
	(version 20260206)
	(generator "pcbnew")
	(generator_version "10.0")
	(general
		(thickness 1.6)
		(legacy_teardrops no)
	)
	(paper "A4")
	(title_block
		(title "timecard-production-celestica-r4006 — R4006-B0001-02_R01.brd")
		(comment 1 "Time Appliance Project (Time Card) / footprints 278-279 of 1113")
	)
	(layers
		(0 "F.Cu" signal "TOP")
		(4 "In1.Cu" signal "L02_GND1")
		(6 "In2.Cu" signal "L03_SIG1")
		(8 "In3.Cu" signal "L04_GND2")
		(10 "In4.Cu" signal "L05_VCC1")
		(12 "In5.Cu" signal "L06_VCC2")
		(14 "In6.Cu" signal "L07_GND3")
		(16 "In7.Cu" signal "L08_SIG2")
		(18 "In8.Cu" signal "L09_GND4")
		(2 "B.Cu" signal "BOTTOM")
		(9 "F.Adhes" user "F.Adhesive")
		(11 "B.Adhes" user "B.Adhesive")
		(13 "F.Paste" user "Package Geometry/Pastemask Top")
		(15 "B.Paste" user "Package Geometry/Pastemask Bottom")
		(5 "F.SilkS" user "Ref Des/Silkscreen Top")
		(7 "B.SilkS" user "Ref Des/Silkscreen Bottom")
		(1 "F.Mask" user "Board Geometry/Soldermask Top")
		(3 "B.Mask" user "Board Geometry/Soldermask Bottom")
		(17 "Dwgs.User" user "User.Drawings")
		(19 "Cmts.User" user "User.Comments")
		(21 "Eco1.User" user "User.Eco1")
		(23 "Eco2.User" user "User.Eco2")
		(25 "Edge.Cuts" user "Board Geometry/Outline")
		(27 "Margin" user)
		(31 "F.CrtYd" user "Package Geometry/Place Bound Top")
		(29 "B.CrtYd" user "Package Geometry/Place Bound Bottom")
		(35 "F.Fab" user "Ref Des/Assembly Top")
		(33 "B.Fab" user "Ref Des/Assembly Bottom")
	)
	(footprint ""
		(layer "F.Cu")
		(at 7.1374 -39.318692 90)
		(property "Reference" "R272"
			(at 2.337308 0.08255 90)
			(unlocked yes)
			(layer "F.SilkS")
			(effects
				(font
					(size 0.635 0.4064)
					(thickness 0.1524)
				)
			)
		)
		(property "Value" "VAL*"
			(at 0.02032 2.13233 90)
			(unlocked yes)
			(layer "F.Fab")
			(hide yes)
			(effects
				(font
					(size 0.7874 0.5842)
					(thickness 0.1524)
				)
			)
		)
		(property "Device Type" "RESISTOR-G155-11000-01,100OHM,A"
			(at 0.008382 1.210564 90)
			(unlocked yes)
			(layer "F.Fab")
			(hide yes)
			(effects
				(font
					(size 0.7874 0.5842)
					(thickness 0.1524)
				)
			)
		)
		(property "User Part Number" "PARTNUM*"
			(at 0.02032 4.024884 90)
			(unlocked yes)
			(layer "Cmts.User")
			(hide yes)
			(effects
				(font
					(size 0.7874 0.5842)
					(thickness 0.1524)
				)
			)
		)
		(property "Tolerance" "TOL*"
			(at 0.044704 3.05435 90)
			(unlocked yes)
			(layer "Cmts.User")
			(hide yes)
			(effects
				(font
					(size 0.7874 0.5842)
					(thickness 0.1524)
				)
			)
		)
		(duplicate_pad_numbers_are_jumpers no)
		(fp_line
			(start 1.143 -0.5588)
			(end -1.143 -0.5588)
			(stroke
				(width 0.1)
				(type default)
			)
			(layer "F.SilkS")
		)
		(fp_line
			(start -1.143 -0.5588)
			(end -1.143 0.5588)
			(stroke
				(width 0.1)
				(type default)
			)
			(layer "F.SilkS")
		)
		(fp_line
			(start 1.143 0.5588)
			(end 1.143 -0.5588)
			(stroke
				(width 0.1)
				(type default)
			)
			(layer "F.SilkS")
		)
		(fp_line
			(start -1.143 0.5588)
			(end 1.143 0.5588)
			(stroke
				(width 0.1)
				(type default)
			)
			(layer "F.SilkS")
		)
		(fp_poly
			(pts
				(xy -1.143 0.5588) (xy 1.143 0.5588) (xy 1.143 -0.5588) (xy -1.143 -0.5588)
			)
			(stroke
				(width 0)
				(type default)
			)
			(fill no)
			(layer "F.CrtYd")
		)
		(fp_line
			(start 0.508 -0.3048)
			(end -0.508 -0.3048)
			(stroke
				(width 0.1)
				(type default)
			)
			(layer "F.Fab")
		)
		(fp_line
			(start -0.508 -0.3048)
			(end -0.508 0.3048)
			(stroke
				(width 0.1)
				(type default)
			)
			(layer "F.Fab")
		)
		(fp_line
			(start 0.508 0.3048)
			(end 0.508 -0.3048)
			(stroke
				(width 0.1)
				(type default)
			)
			(layer "F.Fab")
		)
		(fp_line
			(start -0.508 0.3048)
			(end 0.508 0.3048)
			(stroke
				(width 0.1)
				(type default)
			)
			(layer "F.Fab")
		)
		(pad "1" smd rect
			(at -0.5334 0 90)
			(size 0.7112 0.6096)
			(layers "F.Cu" "F.Mask" "F.Paste")
			(net "FPGA_OUT_SMA1_LED_RED_N")
		)
		(pad "2" smd rect
			(at 0.5334 0 90)
			(size 0.7112 0.6096)
			(layers "F.Cu" "F.Mask" "F.Paste")
			(net "UNNAMED_14_LED4PV14_I265_3")
		)
		(zone
			(layer "F.Cu")
			(hatch none 0.5)
			(connect_pads
				(clearance 0)
			)
			(min_thickness 0.25)
			(keepout
				(tracks allowed)
				(vias not_allowed)
				(pads allowed)
				(copperpour not_allowed)
				(footprints allowed)
			)
			(placement
				(enabled no)
				(sheetname "")
			)
			(fill
				(thermal_gap 0.5)
				(thermal_bridge_width 0.5)
				(island_removal_mode 0)
			)
			(polygon
				(pts
					(xy 7.4422 -39.242492) (xy 7.4422 -39.394892) (xy 6.8326 -39.394892) (xy 6.8326 -39.242492)
				)
			)
		)
		(zone
			(layer "F.Cu")
			(hatch none 0.5)
			(connect_pads
				(clearance 0)
			)
			(min_thickness 0.25)
			(keepout
				(tracks not_allowed)
				(vias allowed)
				(pads allowed)
				(copperpour not_allowed)
				(footprints allowed)
			)
			(placement
				(enabled no)
				(sheetname "")
			)
			(fill
				(thermal_gap 0.5)
				(thermal_bridge_width 0.5)
				(island_removal_mode 0)
			)
			(polygon
				(pts
					(xy 7.4422 -39.242492) (xy 7.4422 -39.394892) (xy 6.8326 -39.394892) (xy 6.8326 -39.242492)
				)
			)
		)
	)
	(footprint ""
		(layer "F.Cu")
		(at 100.076 -56.769)
		(property "Reference" "TP186"
			(at 2.06375 0.4318 90)
			(unlocked yes)
			(layer "F.SilkS")
			(effects
				(font
					(size 0.635 0.4064)
					(thickness 0.1524)
				)
				(justify left)
			)
		)
		(property "Value" ""
			(at 0 0 0)
			(layer "F.Fab")
			(effects
				(font
					(size 1.27 1.27)
				)
			)
		)
		(property "Device Type" "TP_PIONT-TP010CT020B030_PTH-TPA"
			(at -1.341882 0.996696 0)
			(unlocked yes)
			(layer "F.Fab")
			(hide yes)
			(effects
				(font
					(size 0.7874 0.5842)
					(thickness 0.1524)
				)
				(justify left)
			)
		)
		(duplicate_pad_numbers_are_jumpers no)
		(fp_poly
			(pts
				(arc
					(start 0.889 0)
					(mid -0.889 0)
					(end 0.889 0)
				)
			)
			(stroke
				(width 0)
				(type default)
			)
			(fill no)
			(layer "B.CrtYd")
		)
		(fp_poly
			(pts
				(arc
					(start 0.889 0)
					(mid -0.889 0)
					(end 0.889 0)
				)
			)
			(stroke
				(width 0)
				(type default)
			)
			(fill no)
			(layer "F.CrtYd")
		)
		(pad "1" thru_hole circle
			(at 0 0)
			(size 0.508 0.508)
			(drill 0.254)
			(layers "*.Cu" "*.Mask")
			(remove_unused_layers no)
			(net "IO_L23N_16")
			(clearance 0.1016)
			(padstack
				(mode front_inner_back)
				(layer "Inner"
					(shape circle)
					(size 0.508 0.508)
					(clearance 0.1016)
				)
				(layer "B.Cu"
					(shape circle)
					(size 0.762 0.762)
					(clearance -0.0254)
				)
			)
		)
	)
)
